(kicad_pcb
	(version 20260206)
	(generator "pcbnew")
	(generator_version "10.0")
	(general
		(thickness 1.6)
		(legacy_teardrops no)
	)
	(paper "A4")
	(title_block
		(title "timecard-production-celestica-r4006 — R4006-B0001-02_R01.brd")
		(comment 1 "Time Appliance Project (Time Card) / footprints 847-851 of 1113")
	)
	(layers
		(0 "F.Cu" signal "TOP")
		(4 "In1.Cu" signal "L02_GND1")
		(6 "In2.Cu" signal "L03_SIG1")
		(8 "In3.Cu" signal "L04_GND2")
		(10 "In4.Cu" signal "L05_VCC1")
		(12 "In5.Cu" signal "L06_VCC2")
		(14 "In6.Cu" signal "L07_GND3")
		(16 "In7.Cu" signal "L08_SIG2")
		(18 "In8.Cu" signal "L09_GND4")
		(2 "B.Cu" signal "BOTTOM")
		(9 "F.Adhes" user "F.Adhesive")
		(11 "B.Adhes" user "B.Adhesive")
		(13 "F.Paste" user "Package Geometry/Pastemask Top")
		(15 "B.Paste" user "Package Geometry/Pastemask Bottom")
		(5 "F.SilkS" user "Ref Des/Silkscreen Top")
		(7 "B.SilkS" user "Ref Des/Silkscreen Bottom")
		(1 "F.Mask" user "Board Geometry/Soldermask Top")
		(3 "B.Mask" user "Board Geometry/Soldermask Bottom")
		(17 "Dwgs.User" user "User.Drawings")
		(19 "Cmts.User" user "User.Comments")
		(21 "Eco1.User" user "User.Eco1")
		(23 "Eco2.User" user "User.Eco2")
		(25 "Edge.Cuts" user "Board Geometry/Outline")
		(27 "Margin" user)
		(31 "F.CrtYd" user "Package Geometry/Place Bound Top")
		(29 "B.CrtYd" user "Package Geometry/Place Bound Bottom")
		(35 "F.Fab" user "Ref Des/Assembly Top")
		(33 "B.Fab" user "Ref Des/Assembly Bottom")
	)
	(footprint ""
		(layer "B.Cu")
		(at 92.583 -35.433)
		(property "Reference" "L35"
			(at 1.2065 1.43637 0)
			(unlocked yes)
			(layer "B.SilkS")
			(effects
				(font
					(size 0.7874 0.5842)
					(thickness 0.1524)
				)
				(justify left mirror)
			)
		)
		(property "Value" "VAL*"
			(at 0.9398 3.70967 0)
			(unlocked yes)
			(layer "B.Fab")
			(hide yes)
			(effects
				(font
					(size 0.7874 0.5842)
					(thickness 0.1524)
				)
				(justify left mirror)
			)
		)
		(property "Device Type" "FERRITEBEAD-G191-10100-01,120OA"
			(at 0.9906 1.22047 0)
			(unlocked yes)
			(layer "B.Fab")
			(hide yes)
			(effects
				(font
					(size 0.7874 0.5842)
					(thickness 0.1524)
				)
				(justify left mirror)
			)
		)
		(property "User Part Number" "PARTNUM*"
			(at 2.54 2.46507 0)
			(unlocked yes)
			(layer "Cmts.User")
			(hide yes)
			(effects
				(font
					(size 0.7874 0.5842)
					(thickness 0.1524)
				)
				(justify left mirror)
			)
		)
		(property "Tolerance" "TOL*"
			(at 0.9906 5.00507 0)
			(unlocked yes)
			(layer "Cmts.User")
			(hide yes)
			(effects
				(font
					(size 0.7874 0.5842)
					(thickness 0.1524)
				)
				(justify left mirror)
			)
		)
		(duplicate_pad_numbers_are_jumpers no)
		(fp_line
			(start -1.3208 -0.7112)
			(end -1.3208 0.7112)
			(stroke
				(width 0.1)
				(type default)
			)
			(layer "B.SilkS")
		)
		(fp_line
			(start -1.3208 0.7112)
			(end 1.3208 0.7112)
			(stroke
				(width 0.1)
				(type default)
			)
			(layer "B.SilkS")
		)
		(fp_line
			(start 1.3208 -0.7112)
			(end -1.3208 -0.7112)
			(stroke
				(width 0.1)
				(type default)
			)
			(layer "B.SilkS")
		)
		(fp_line
			(start 1.3208 0.7112)
			(end 1.3208 -0.7112)
			(stroke
				(width 0.1)
				(type default)
			)
			(layer "B.SilkS")
		)
		(fp_rect
			(start 1.3208 0.7112)
			(end -1.3208 -0.7112)
			(stroke
				(width 0)
				(type default)
			)
			(fill no)
			(layer "B.CrtYd")
		)
		(fp_line
			(start -0.8128 -0.4572)
			(end -0.8128 0.4572)
			(stroke
				(width 0.1)
				(type default)
			)
			(layer "B.Fab")
		)
		(fp_line
			(start -0.8128 0.4572)
			(end 0.8128 0.4572)
			(stroke
				(width 0.1)
				(type default)
			)
			(layer "B.Fab")
		)
		(fp_line
			(start 0.8128 -0.4572)
			(end -0.8128 -0.4572)
			(stroke
				(width 0.1)
				(type default)
			)
			(layer "B.Fab")
		)
		(fp_line
			(start 0.8128 0.4572)
			(end 0.8128 -0.4572)
			(stroke
				(width 0.1)
				(type default)
			)
			(layer "B.Fab")
		)
		(pad "1" smd rect
			(at 0.6858 0 180)
			(size 0.762 0.8636)
			(layers "B.Cu" "B.Mask" "B.Paste")
			(net "FPGA_MGTAVTT")
		)
		(pad "2" smd rect
			(at -0.6858 0 180)
			(size 0.762 0.8636)
			(layers "B.Cu" "B.Mask" "B.Paste")
			(net "XP1R2V_FPGA")
		)
		(zone
			(layer "B.Cu")
			(hatch none 0.5)
			(connect_pads
				(clearance 0)
			)
			(min_thickness 0.25)
			(keepout
				(tracks not_allowed)
				(vias allowed)
				(pads allowed)
				(copperpour not_allowed)
				(footprints allowed)
			)
			(placement
				(enabled no)
				(sheetname "")
			)
			(fill
				(thermal_gap 0.5)
				(thermal_bridge_width 0.5)
				(island_removal_mode 0)
			)
			(polygon
				(pts
					(xy 92.7354 -34.9758) (xy 92.7354 -35.8902) (xy 92.4306 -35.8902) (xy 92.4306 -34.9758)
				)
			)
		)
		(zone
			(layer "B.Cu")
			(hatch none 0.5)
			(connect_pads
				(clearance 0)
			)
			(min_thickness 0.25)
			(keepout
				(tracks allowed)
				(vias not_allowed)
				(pads allowed)
				(copperpour not_allowed)
				(footprints allowed)
			)
			(placement
				(enabled no)
				(sheetname "")
			)
			(fill
				(thermal_gap 0.5)
				(thermal_bridge_width 0.5)
				(island_removal_mode 0)
			)
			(polygon
				(pts
					(xy 92.7354 -34.9758) (xy 92.7354 -35.8902) (xy 92.4306 -35.8902) (xy 92.4306 -34.9758)
				)
			)
		)
	)
	(footprint ""
		(layer "B.Cu")
		(at 77.3938 -85.09)
		(property "Reference" "R151"
			(at -1.1938 -2.24663 0)
			(unlocked yes)
			(layer "B.SilkS")
			(effects
				(font
					(size 0.7874 0.5842)
					(thickness 0.1524)
				)
				(justify mirror)
			)
		)
		(property "Value" "VAL*"
			(at -0.02032 2.13233 0)
			(unlocked yes)
			(layer "B.Fab")
			(hide yes)
			(effects
				(font
					(size 0.7874 0.5842)
					(thickness 0.1524)
				)
				(justify mirror)
			)
		)
		(property "Tolerance" "TOL*"
			(at -0.044704 3.05435 0)
			(unlocked yes)
			(layer "Cmts.User")
			(hide yes)
			(effects
				(font
					(size 0.7874 0.5842)
					(thickness 0.1524)
				)
				(justify mirror)
			)
		)
		(property "User Part Number" "PARTNUM*"
			(at -0.02032 4.024884 0)
			(unlocked yes)
			(layer "Cmts.User")
			(hide yes)
			(effects
				(font
					(size 0.7874 0.5842)
					(thickness 0.1524)
				)
				(justify mirror)
			)
		)
		(property "Device Type" "RESISTOR-G155-14701-01,4.7KOHMA"
			(at -0.008382 1.210564 0)
			(unlocked yes)
			(layer "B.Fab")
			(hide yes)
			(effects
				(font
					(size 0.7874 0.5842)
					(thickness 0.1524)
				)
				(justify mirror)
			)
		)
		(duplicate_pad_numbers_are_jumpers no)
		(fp_line
			(start -1.143 -0.5588)
			(end 1.143 -0.5588)
			(stroke
				(width 0.1)
				(type default)
			)
			(layer "B.SilkS")
		)
		(fp_line
			(start -1.143 0.5588)
			(end -1.143 -0.5588)
			(stroke
				(width 0.1)
				(type default)
			)
			(layer "B.SilkS")
		)
		(fp_line
			(start 1.143 -0.5588)
			(end 1.143 0.5588)
			(stroke
				(width 0.1)
				(type default)
			)
			(layer "B.SilkS")
		)
		(fp_line
			(start 1.143 0.5588)
			(end -1.143 0.5588)
			(stroke
				(width 0.1)
				(type default)
			)
			(layer "B.SilkS")
		)
		(fp_rect
			(start 1.143 -0.5588)
			(end -1.143 0.5588)
			(stroke
				(width 0)
				(type default)
			)
			(fill no)
			(layer "B.CrtYd")
		)
		(fp_line
			(start -0.508 -0.3048)
			(end 0.508 -0.3048)
			(stroke
				(width 0.1)
				(type default)
			)
			(layer "B.Fab")
		)
		(fp_line
			(start -0.508 0.3048)
			(end -0.508 -0.3048)
			(stroke
				(width 0.1)
				(type default)
			)
			(layer "B.Fab")
		)
		(fp_line
			(start 0.508 -0.3048)
			(end 0.508 0.3048)
			(stroke
				(width 0.1)
				(type default)
			)
			(layer "B.Fab")
		)
		(fp_line
			(start 0.508 0.3048)
			(end -0.508 0.3048)
			(stroke
				(width 0.1)
				(type default)
			)
			(layer "B.Fab")
		)
		(pad "1" smd rect
			(at 0.5334 0 180)
			(size 0.7112 0.6096)
			(layers "B.Cu" "B.Mask" "B.Paste")
			(net "XP3R3V_FPGA")
		)
		(pad "2" smd rect
			(at -0.5334 0 180)
			(size 0.7112 0.6096)
			(layers "B.Cu" "B.Mask" "B.Paste")
			(net "UNNAMED_5_PCA9546APWTSSOP16_I_2")
		)
		(zone
			(layer "B.Cu")
			(hatch none 0.5)
			(connect_pads
				(clearance 0)
			)
			(min_thickness 0.25)
			(keepout
				(tracks allowed)
				(vias not_allowed)
				(pads allowed)
				(copperpour not_allowed)
				(footprints allowed)
			)
			(placement
				(enabled no)
				(sheetname "")
			)
			(fill
				(thermal_gap 0.5)
				(thermal_bridge_width 0.5)
				(island_removal_mode 0)
			)
			(polygon
				(pts
					(xy 77.47 -85.3948) (xy 77.3176 -85.3948) (xy 77.3176 -84.7852) (xy 77.47 -84.7852)
				)
			)
		)
	)
	(footprint ""
		(layer "B.Cu")
		(at 36.9824 -105.2068)
		(property "Reference" "R32"
			(at -2.8194 -0.68453 0)
			(unlocked yes)
			(layer "B.SilkS")
			(effects
				(font
					(size 0.7874 0.5842)
					(thickness 0.1524)
				)
				(justify mirror)
			)
		)
		(property "Value" "VAL*"
			(at -0.02032 2.13233 0)
			(unlocked yes)
			(layer "B.Fab")
			(hide yes)
			(effects
				(font
					(size 0.7874 0.5842)
					(thickness 0.1524)
				)
				(justify mirror)
			)
		)
		(property "Tolerance" "TOL*"
			(at -0.044704 3.05435 0)
			(unlocked yes)
			(layer "Cmts.User")
			(hide yes)
			(effects
				(font
					(size 0.7874 0.5842)
					(thickness 0.1524)
				)
				(justify mirror)
			)
		)
		(property "User Part Number" "PARTNUM*"
			(at -0.02032 4.024884 0)
			(unlocked yes)
			(layer "Cmts.User")
			(hide yes)
			(effects
				(font
					(size 0.7874 0.5842)
					(thickness 0.1524)
				)
				(justify mirror)
			)
		)
		(property "Device Type" "RESISTOR-G155-03241-01,3.24KOHA"
			(at -0.008382 1.210564 0)
			(unlocked yes)
			(layer "B.Fab")
			(hide yes)
			(effects
				(font
					(size 0.7874 0.5842)
					(thickness 0.1524)
				)
				(justify mirror)
			)
		)
		(duplicate_pad_numbers_are_jumpers no)
		(fp_line
			(start -1.143 -0.5588)
			(end 1.143 -0.5588)
			(stroke
				(width 0.1)
				(type default)
			)
			(layer "B.SilkS")
		)
		(fp_line
			(start -1.143 0.5588)
			(end -1.143 -0.5588)
			(stroke
				(width 0.1)
				(type default)
			)
			(layer "B.SilkS")
		)
		(fp_line
			(start 1.143 -0.5588)
			(end 1.143 0.5588)
			(stroke
				(width 0.1)
				(type default)
			)
			(layer "B.SilkS")
		)
		(fp_line
			(start 1.143 0.5588)
			(end -1.143 0.5588)
			(stroke
				(width 0.1)
				(type default)
			)
			(layer "B.SilkS")
		)
		(fp_poly
			(pts
				(xy 1.143 0.5588) (xy -1.143 0.5588) (xy -1.143 -0.5588) (xy 1.143 -0.5588)
			)
			(stroke
				(width 0)
				(type default)
			)
			(fill no)
			(layer "B.CrtYd")
		)
		(fp_line
			(start -0.508 -0.3048)
			(end 0.508 -0.3048)
			(stroke
				(width 0.1)
				(type default)
			)
			(layer "B.Fab")
		)
		(fp_line
			(start -0.508 0.3048)
			(end -0.508 -0.3048)
			(stroke
				(width 0.1)
				(type default)
			)
			(layer "B.Fab")
		)
		(fp_line
			(start 0.508 -0.3048)
			(end 0.508 0.3048)
			(stroke
				(width 0.1)
				(type default)
			)
			(layer "B.Fab")
		)
		(fp_line
			(start 0.508 0.3048)
			(end -0.508 0.3048)
			(stroke
				(width 0.1)
				(type default)
			)
			(layer "B.Fab")
		)
		(pad "1" smd rect
			(at 0.5334 0 180)
			(size 0.7112 0.6096)
			(layers "B.Cu" "B.Mask" "B.Paste")
			(net "XP5R0V_FB_R_TO_AGND")
		)
		(pad "2" smd rect
			(at -0.5334 0 180)
			(size 0.7112 0.6096)
			(layers "B.Cu" "B.Mask" "B.Paste")
			(net "XP5R0V_AGND")
		)
		(zone
			(layer "B.Cu")
			(hatch none 0.5)
			(connect_pads
				(clearance 0)
			)
			(min_thickness 0.25)
			(keepout
				(tracks allowed)
				(vias not_allowed)
				(pads allowed)
				(copperpour not_allowed)
				(footprints allowed)
			)
			(placement
				(enabled no)
				(sheetname "")
			)
			(fill
				(thermal_gap 0.5)
				(thermal_bridge_width 0.5)
				(island_removal_mode 0)
			)
			(polygon
				(pts
					(xy 37.0586 -104.902) (xy 37.0586 -105.5116) (xy 36.9062 -105.5116) (xy 36.9062 -104.902)
				)
			)
		)
		(zone
			(layer "B.Cu")
			(hatch none 0.5)
			(connect_pads
				(clearance 0)
			)
			(min_thickness 0.25)
			(keepout
				(tracks not_allowed)
				(vias allowed)
				(pads allowed)
				(copperpour not_allowed)
				(footprints allowed)
			)
			(placement
				(enabled no)
				(sheetname "")
			)
			(fill
				(thermal_gap 0.5)
				(thermal_bridge_width 0.5)
				(island_removal_mode 0)
			)
			(polygon
				(pts
					(xy 37.0586 -104.902) (xy 37.0586 -105.5116) (xy 36.9062 -105.5116) (xy 36.9062 -104.902)
				)
			)
		)
	)
	(footprint ""
		(layer "B.Cu")
		(at 107.347004 -42.82313)
		(property "Reference" "C109"
			(at -41.180004 0.94488 0)
			(unlocked yes)
			(layer "B.SilkS")
			(effects
				(font
					(size 0.635 0.4064)
					(thickness 0.1524)
				)
				(justify mirror)
			)
		)
		(property "Value" "VAL*"
			(at 0 3.718306 0)
			(unlocked yes)
			(layer "B.Fab")
			(hide yes)
			(effects
				(font
					(size 0.7874 0.5842)
					(thickness 0.127)
				)
				(justify mirror)
			)
		)
		(property "Device Type" "CAPACITOR-G105-0B104-CK,0.1UF,A"
			(at 0 1.432306 0)
			(unlocked yes)
			(layer "B.Fab")
			(hide yes)
			(effects
				(font
					(size 0.7874 0.5842)
					(thickness 0.127)
				)
				(justify mirror)
			)
		)
		(property "User Part Number" "PARTNUM*"
			(at 0 2.575306 0)
			(unlocked yes)
			(layer "Cmts.User")
			(hide yes)
			(effects
				(font
					(size 0.7874 0.5842)
					(thickness 0.127)
				)
				(justify mirror)
			)
		)
		(property "Tolerance" "TOL*"
			(at 0 4.861306 0)
			(unlocked yes)
			(layer "Cmts.User")
			(hide yes)
			(effects
				(font
					(size 0.7874 0.5842)
					(thickness 0.127)
				)
				(justify mirror)
			)
		)
		(duplicate_pad_numbers_are_jumpers no)
		(fp_line
			(start -0.970026 -0.4699)
			(end -0.970026 0.4699)
			(stroke
				(width 0.1)
				(type default)
			)
			(layer "B.SilkS")
		)
		(fp_line
			(start -0.970026 0.4699)
			(end 0.970026 0.4699)
			(stroke
				(width 0.1)
				(type default)
			)
			(layer "B.SilkS")
		)
		(fp_line
			(start 0.970026 -0.4699)
			(end -0.970026 -0.4699)
			(stroke
				(width 0.1)
				(type default)
			)
			(layer "B.SilkS")
		)
		(fp_line
			(start 0.970026 0.4699)
			(end 0.970026 -0.4699)
			(stroke
				(width 0.1)
				(type default)
			)
			(layer "B.SilkS")
		)
		(fp_poly
			(pts
				(xy 0.970026 0.4699) (xy -0.970026 0.4699) (xy -0.970026 -0.4699) (xy 0.970026 -0.4699)
			)
			(stroke
				(width 0)
				(type default)
			)
			(fill no)
			(layer "B.CrtYd")
		)
		(fp_line
			(start -0.508 -0.3048)
			(end -0.508 0.3048)
			(stroke
				(width 0.1)
				(type default)
			)
			(layer "B.Fab")
		)
		(fp_line
			(start -0.508 0.3048)
			(end 0.508 0.3048)
			(stroke
				(width 0.1)
				(type default)
			)
			(layer "B.Fab")
		)
		(fp_line
			(start 0.508 -0.3048)
			(end -0.508 -0.3048)
			(stroke
				(width 0.1)
				(type default)
			)
			(layer "B.Fab")
		)
		(fp_line
			(start 0.508 0.3048)
			(end 0.508 -0.3048)
			(stroke
				(width 0.1)
				(type default)
			)
			(layer "B.Fab")
		)
		(pad "1" smd circle
			(at 0.500126 0 180)
			(size 0.635 0.635)
			(layers "B.Cu" "B.Mask" "B.Paste")
			(net "XP1R0V_FPGA_VCCINT")
		)
		(pad "2" smd circle
			(at -0.500126 0 180)
			(size 0.635 0.635)
			(layers "B.Cu" "B.Mask" "B.Paste")
			(net "SG")
		)
	)
	(footprint ""
		(layer "B.Cu")
		(at 113.847118 -40.323008 90)
		(property "Reference" "C152"
			(at -1.397508 -42.017188 270)
			(unlocked yes)
			(layer "B.SilkS")
			(effects
				(font
					(size 0.635 0.4064)
					(thickness 0.1524)
				)
				(justify mirror)
			)
		)
		(property "Value" "VAL*"
			(at 0 3.718306 90)
			(unlocked yes)
			(layer "B.Fab")
			(hide yes)
			(effects
				(font
					(size 0.7874 0.5842)
					(thickness 0.127)
				)
				(justify mirror)
			)
		)
		(property "Device Type" "CAPACITOR-G105-0B104-CK,0.1UF,A"
			(at 0 1.432306 90)
			(unlocked yes)
			(layer "B.Fab")
			(hide yes)
			(effects
				(font
					(size 0.7874 0.5842)
					(thickness 0.127)
				)
				(justify mirror)
			)
		)
		(property "User Part Number" "PARTNUM*"
			(at 0 2.575306 90)
			(unlocked yes)
			(layer "Cmts.User")
			(hide yes)
			(effects
				(font
					(size 0.7874 0.5842)
					(thickness 0.127)
				)
				(justify mirror)
			)
		)
		(property "Tolerance" "TOL*"
			(at 0 4.861306 90)
			(unlocked yes)
			(layer "Cmts.User")
			(hide yes)
			(effects
				(font
					(size 0.7874 0.5842)
					(thickness 0.127)
				)
				(justify mirror)
			)
		)
		(duplicate_pad_numbers_are_jumpers no)
		(fp_line
			(start 0.970026 -0.4699)
			(end -0.970026 -0.4699)
			(stroke
				(width 0.1)
				(type default)
			)
			(layer "B.SilkS")
		)
		(fp_line
			(start -0.970026 -0.4699)
			(end -0.970026 0.4699)
			(stroke
				(width 0.1)
				(type default)
			)
			(layer "B.SilkS")
		)
		(fp_line
			(start 0.970026 0.4699)
			(end 0.970026 -0.4699)
			(stroke
				(width 0.1)
				(type default)
			)
			(layer "B.SilkS")
		)
		(fp_line
			(start -0.970026 0.4699)
			(end 0.970026 0.4699)
			(stroke
				(width 0.1)
				(type default)
			)
			(layer "B.SilkS")
		)
		(fp_poly
			(pts
				(xy 0.970026 0.4699) (xy -0.970026 0.4699) (xy -0.970026 -0.4699) (xy 0.970026 -0.4699)
			)
			(stroke
				(width 0)
				(type default)
			)
			(fill no)
			(layer "B.CrtYd")
		)
		(fp_line
			(start 0.508 -0.3048)
			(end -0.508 -0.3048)
			(stroke
				(width 0.1)
				(type default)
			)
			(layer "B.Fab")
		)
		(fp_line
			(start -0.508 -0.3048)
			(end -0.508 0.3048)
			(stroke
				(width 0.1)
				(type default)
			)
			(layer "B.Fab")
		)
		(fp_line
			(start 0.508 0.3048)
			(end 0.508 -0.3048)
			(stroke
				(width 0.1)
				(type default)
			)
			(layer "B.Fab")
		)
		(fp_line
			(start -0.508 0.3048)
			(end 0.508 0.3048)
			(stroke
				(width 0.1)
				(type default)
			)
			(layer "B.Fab")
		)
		(pad "1" smd circle
			(at 0.500126 0 270)
			(size 0.635 0.635)
			(layers "B.Cu" "B.Mask" "B.Paste")
			(net "XP1R0V_FPGA_VCCINT")
		)
		(pad "2" smd circle
			(at -0.500126 0 270)
			(size 0.635 0.635)
			(layers "B.Cu" "B.Mask" "B.Paste")
			(net "SG")
		)
	)
)
